(kicad_pcb
	(version 20260206)
	(generator "pcbnew")
	(generator_version "10.0")
	(general
		(thickness 1.6)
		(legacy_teardrops no)
	)
	(paper "A4")
	(title_block
		(title "panther-plus-userver — 13130-1b_20150205.brd")
		(comment 1 "Honey Badger (Wiwynn) / footprint 282 of 1509 (U13), pads 357-475 of 1283")
	)
	(layers
		(0 "F.Cu" signal "TOP")
		(4 "In1.Cu" signal "L2")
		(6 "In2.Cu" signal "L3")
		(8 "In3.Cu" signal "L4")
		(10 "In4.Cu" signal "L5")
		(12 "In5.Cu" signal "L6")
		(14 "In6.Cu" signal "L7")
		(16 "In7.Cu" signal "L8")
		(18 "In8.Cu" signal "L9")
		(20 "In9.Cu" signal "L10")
		(22 "In10.Cu" signal "L11")
		(2 "B.Cu" signal "BOTTOM")
		(9 "F.Adhes" user "F.Adhesive")
		(11 "B.Adhes" user "B.Adhesive")
		(13 "F.Paste" user "Package Geometry/Pastemask Top")
		(15 "B.Paste" user "Package Geometry/Pastemask Bottom")
		(5 "F.SilkS" user "Ref Des/Silkscreen Top")
		(7 "B.SilkS" user "Ref Des/Silkscreen Bottom")
		(1 "F.Mask" user "Board Geometry/Soldermask Top")
		(3 "B.Mask" user "Board Geometry/Soldermask Bottom")
		(17 "Dwgs.User" user "User.Drawings")
		(19 "Cmts.User" user "User.Comments")
		(21 "Eco1.User" user "User.Eco1")
		(23 "Eco2.User" user "User.Eco2")
		(25 "Edge.Cuts" user "Board Geometry/Outline")
		(27 "Margin" user)
		(31 "F.CrtYd" user "Package Geometry/Place Bound Top")
		(29 "B.CrtYd" user "Package Geometry/Place Bound Bottom")
		(35 "F.Fab" user "Ref Des/Assembly Top")
		(33 "B.Fab" user "Ref Des/Assembly Bottom")
	)
	(footprint ""
		(layer "F.Cu")
		(at 95.849948 -39.200074 180)
		(property "Reference" "U13"
			(at 0 0 180)
			(layer "F.SilkS")
			(hide yes)
			(effects
				(font
					(size 1.27 1.27)
				)
			)
		)
		(property "Value" "AVOTON-GP"
			(at -25.0317 -2.4892 180)
			(unlocked yes)
			(layer "F.Fab")
			(hide yes)
			(effects
				(font
					(size 1.016 1.016)
					(thickness 0.1524)
				)
			)
		)
		(property "Device Type" "BGA1283M3428-3H197"
			(at -25.0317 -4.0132 180)
			(unlocked yes)
			(layer "F.Fab")
			(hide yes)
			(effects
				(font
					(size 1.016 1.016)
					(thickness 0.1524)
				)
			)
		)
		(duplicate_pad_numbers_are_jumpers no)
		(pad "AR11" smd circle
			(at -11.05916 3.74142 180)
			(size 0.3048 0.3048)
			(layers "F.Cu" "F.Mask" "F.Paste")
			(net "M_A_DQ11")
		)
		(pad "AR13" smd circle
			(at -10.29716 3.74142 180)
			(size 0.3048 0.3048)
			(layers "F.Cu" "F.Mask" "F.Paste")
			(net "GND")
		)
		(pad "AR14" smd circle
			(at -9.53516 3.74142 180)
			(size 0.3048 0.3048)
			(layers "F.Cu" "F.Mask" "F.Paste")
			(net "M_A_DQ8")
		)
		(pad "AR16" smd circle
			(at -8.77316 3.74142 180)
			(size 0.3048 0.3048)
			(layers "F.Cu" "F.Mask" "F.Paste")
			(net "M_A_DQ12")
		)
		(pad "AR17" smd circle
			(at -8.01116 3.74142 180)
			(size 0.3048 0.3048)
			(layers "F.Cu" "F.Mask" "F.Paste")
			(net "GND")
		)
		(pad "AR19" smd circle
			(at -7.24916 3.74142 180)
			(size 0.3048 0.3048)
			(layers "F.Cu" "F.Mask" "F.Paste")
			(net "GND")
		)
		(pad "AR48" smd circle
			(at 7.24916 3.50266 180)
			(size 0.3048 0.3048)
			(layers "F.Cu" "F.Mask" "F.Paste")
			(net "PD_USB_OBSP")
		)
		(pad "AR50" smd circle
			(at 8.01116 3.50266 180)
			(size 0.3048 0.3048)
			(layers "F.Cu" "F.Mask" "F.Paste")
			(net "GND")
		)
		(pad "AR51" smd circle
			(at 8.77316 3.50266 180)
			(size 0.3048 0.3048)
			(layers "F.Cu" "F.Mask" "F.Paste")
			(net "Net_84")
		)
		(pad "AR53" smd circle
			(at 9.53516 3.50266 180)
			(size 0.3048 0.3048)
			(layers "F.Cu" "F.Mask" "F.Paste")
			(net "Net_83")
		)
		(pad "AR54" smd circle
			(at 10.29716 3.50266 180)
			(size 0.3048 0.3048)
			(layers "F.Cu" "F.Mask" "F.Paste")
			(net "Net_85")
		)
		(pad "AR56" smd circle
			(at 11.05916 3.50266 180)
			(size 0.3048 0.3048)
			(layers "F.Cu" "F.Mask" "F.Paste")
			(net "GND")
		)
		(pad "AR57" smd circle
			(at 11.82116 3.50266 180)
			(size 0.3048 0.3048)
			(layers "F.Cu" "F.Mask" "F.Paste")
			(net "XDP_DFX_PORT3")
		)
		(pad "AR59" smd circle
			(at 12.58316 3.50266 180)
			(size 0.3048 0.3048)
			(layers "F.Cu" "F.Mask" "F.Paste")
			(net "XDP_DFX_PORT15")
		)
		(pad "AR60" smd circle
			(at 13.34516 3.50266 180)
			(size 0.3048 0.3048)
			(layers "F.Cu" "F.Mask" "F.Paste")
			(net "GND")
		)
		(pad "AR62" smd circle
			(at 14.06398 3.88874 180)
			(size 0.3048 0.3048)
			(layers "F.Cu" "F.Mask" "F.Paste")
			(net "GND")
		)
		(pad "AR63" smd circle
			(at 14.75232 3.71856 180)
			(size 0.3048 0.3048)
			(layers "F.Cu" "F.Mask" "F.Paste")
			(net "SMB_CLK1_SPKR")
		)
		(pad "AR65" smd circle
			(at 15.80642 3.63982 180)
			(size 0.3048 0.3048)
			(layers "F.Cu" "F.Mask" "F.Paste")
			(net "SMBUS_PECI_CLK")
		)
		(pad "AT5" smd circle
			(at -14.06398 4.09448 180)
			(size 0.3048 0.3048)
			(layers "F.Cu" "F.Mask" "F.Paste")
			(net "GND")
		)
		(pad "AT7" smd circle
			(at -13.34516 4.44246 180)
			(size 0.3048 0.3048)
			(layers "F.Cu" "F.Mask" "F.Paste")
			(net "M_A_DQS_DP1")
		)
		(pad "AT8" smd circle
			(at -12.58316 4.44246 180)
			(size 0.3048 0.3048)
			(layers "F.Cu" "F.Mask" "F.Paste")
			(net "M_A_DQ14")
		)
		(pad "AT10" smd circle
			(at -11.82116 4.44246 180)
			(size 0.3048 0.3048)
			(layers "F.Cu" "F.Mask" "F.Paste")
			(net "M_A_DQ10")
		)
		(pad "AT11" smd circle
			(at -11.05916 4.44246 180)
			(size 0.3048 0.3048)
			(layers "F.Cu" "F.Mask" "F.Paste")
			(net "GND")
		)
		(pad "AT13" smd circle
			(at -10.29716 4.44246 180)
			(size 0.3048 0.3048)
			(layers "F.Cu" "F.Mask" "F.Paste")
			(net "M_A_DQ9")
		)
		(pad "AT14" smd circle
			(at -9.53516 4.44246 180)
			(size 0.3048 0.3048)
			(layers "F.Cu" "F.Mask" "F.Paste")
			(net "M_A_DQ13")
		)
		(pad "AT16" smd circle
			(at -8.77316 4.44246 180)
			(size 0.3048 0.3048)
			(layers "F.Cu" "F.Mask" "F.Paste")
			(net "GND")
		)
		(pad "AT17" smd circle
			(at -8.01116 4.44246 180)
			(size 0.3048 0.3048)
			(layers "F.Cu" "F.Mask" "F.Paste")
			(net "GND")
		)
		(pad "AT19" smd circle
			(at -7.24916 4.44246 180)
			(size 0.3048 0.3048)
			(layers "F.Cu" "F.Mask" "F.Paste")
			(net "GND")
		)
		(pad "AT21" smd circle
			(at -5.99948 4.0005 180)
			(size 0.381 0.381)
			(layers "F.Cu" "F.Mask" "F.Paste")
			(net "P1V0")
		)
		(pad "AT23" smd circle
			(at -5.20192 4.0005 180)
			(size 0.381 0.381)
			(layers "F.Cu" "F.Mask" "F.Paste")
			(net "P1V0")
		)
		(pad "AT25" smd circle
			(at -4.39928 4.0005 180)
			(size 0.381 0.381)
			(layers "F.Cu" "F.Mask" "F.Paste")
			(net "P1V0")
		)
		(pad "AT26" smd circle
			(at -3.60172 4.0005 180)
			(size 0.381 0.381)
			(layers "F.Cu" "F.Mask" "F.Paste")
			(net "P1V0")
		)
		(pad "AT28" smd circle
			(at -2.79908 4.0005 180)
			(size 0.381 0.381)
			(layers "F.Cu" "F.Mask" "F.Paste")
			(net "P1V0")
		)
		(pad "AT29" smd circle
			(at -2.00152 4.0005 180)
			(size 0.381 0.381)
			(layers "F.Cu" "F.Mask" "F.Paste")
			(net "VCCCLKDDR0")
		)
		(pad "AT31" smd circle
			(at -1.19888 4.0005 180)
			(size 0.381 0.381)
			(layers "F.Cu" "F.Mask" "F.Paste")
			(net "P1V35")
		)
		(pad "AT32" smd circle
			(at -0.40132 4.0005 180)
			(size 0.381 0.381)
			(layers "F.Cu" "F.Mask" "F.Paste")
			(net "VCCACKDDR0")
		)
		(pad "AT34" smd circle
			(at 0.40132 4.0005 180)
			(size 0.381 0.381)
			(layers "F.Cu" "F.Mask" "F.Paste")
			(net "TP_CPU_RSVD2")
		)
		(pad "AT36" smd circle
			(at 1.19888 4.0005 180)
			(size 0.381 0.381)
			(layers "F.Cu" "F.Mask" "F.Paste")
			(net "P1V0")
		)
		(pad "AT38" smd circle
			(at 2.00152 4.0005 180)
			(size 0.381 0.381)
			(layers "F.Cu" "F.Mask" "F.Paste")
			(net "P1V0")
		)
		(pad "AT39" smd circle
			(at 2.79908 4.0005 180)
			(size 0.381 0.381)
			(layers "F.Cu" "F.Mask" "F.Paste")
			(net "P1V0")
		)
		(pad "AT41" smd circle
			(at 3.60172 4.0005 180)
			(size 0.381 0.381)
			(layers "F.Cu" "F.Mask" "F.Paste")
			(net "P1V0_STBY")
		)
		(pad "AT42" smd circle
			(at 4.39928 4.0005 180)
			(size 0.381 0.381)
			(layers "F.Cu" "F.Mask" "F.Paste")
			(net "P1V0")
		)
		(pad "AT44" smd circle
			(at 5.20192 4.0005 180)
			(size 0.381 0.381)
			(layers "F.Cu" "F.Mask" "F.Paste")
			(net "GND")
		)
		(pad "AT46" smd circle
			(at 5.99948 4.0005 180)
			(size 0.381 0.381)
			(layers "F.Cu" "F.Mask" "F.Paste")
			(net "PD_USB_RCOMP")
		)
		(pad "AT48" smd circle
			(at 7.24916 4.2037 180)
			(size 0.3048 0.3048)
			(layers "F.Cu" "F.Mask" "F.Paste")
			(net "PD_USB_RCOMP")
		)
		(pad "AT50" smd circle
			(at 8.01116 4.2037 180)
			(size 0.3048 0.3048)
			(layers "F.Cu" "F.Mask" "F.Paste")
			(net "IRQ_CPU_SERIAL")
		)
		(pad "AT51" smd circle
			(at 8.77316 4.2037 180)
			(size 0.3048 0.3048)
			(layers "F.Cu" "F.Mask" "F.Paste")
			(net "TP_CPU_RSVD1")
		)
		(pad "AT53" smd circle
			(at 9.53516 4.2037 180)
			(size 0.3048 0.3048)
			(layers "F.Cu" "F.Mask" "F.Paste")
			(net "GND")
		)
		(pad "AT54" smd circle
			(at 10.29716 4.2037 180)
			(size 0.3048 0.3048)
			(layers "F.Cu" "F.Mask" "F.Paste")
			(net "XDP_DFX_PORT4")
		)
		(pad "AT56" smd circle
			(at 11.05916 4.2037 180)
			(size 0.3048 0.3048)
			(layers "F.Cu" "F.Mask" "F.Paste")
			(net "CPU_THERMTRIP#")
		)
		(pad "AT57" smd circle
			(at 11.82116 4.2037 180)
			(size 0.3048 0.3048)
			(layers "F.Cu" "F.Mask" "F.Paste")
			(net "GND")
		)
		(pad "AT59" smd circle
			(at 12.58316 4.2037 180)
			(size 0.3048 0.3048)
			(layers "F.Cu" "F.Mask" "F.Paste")
			(net "XDP_DFX_PORT11")
		)
		(pad "AT60" smd circle
			(at 13.34516 4.2037 180)
			(size 0.3048 0.3048)
			(layers "F.Cu" "F.Mask" "F.Paste")
			(net "XDP_DFX_PORT9")
		)
		(pad "AT63" smd circle
			(at 14.5415 4.39928 180)
			(size 0.3048 0.3048)
			(layers "F.Cu" "F.Mask" "F.Paste")
			(net "BD_ID_0")
		)
		(pad "AT64" smd circle
			(at 15.3035 4.45008 180)
			(size 0.3048 0.3048)
			(layers "F.Cu" "F.Mask" "F.Paste")
			(net "GND")
		)
		(pad "AT66" smd oval
			(at 16.24838 4.39928 180)
			(size 0.3429 0.254)
			(layers "F.Cu" "F.Mask" "F.Paste")
			(net "GND")
		)
		(pad "AU1" smd oval
			(at -16.24838 4.60756 180)
			(size 0.3429 0.254)
			(layers "F.Cu" "F.Mask" "F.Paste")
			(net "M_A_DQ26")
		)
		(pad "AU3" smd circle
			(at -15.3035 4.55676 180)
			(size 0.3048 0.3048)
			(layers "F.Cu" "F.Mask" "F.Paste")
			(net "M_A_DQ27")
		)
		(pad "AU4" smd circle
			(at -14.5415 4.60756 180)
			(size 0.3048 0.3048)
			(layers "F.Cu" "F.Mask" "F.Paste")
			(net "GND")
		)
		(pad "AU21" smd circle
			(at -5.99948 4.8006 180)
			(size 0.381 0.381)
			(layers "F.Cu" "F.Mask" "F.Paste")
			(net "P1V0")
		)
		(pad "AU23" smd circle
			(at -5.20192 4.8006 180)
			(size 0.381 0.381)
			(layers "F.Cu" "F.Mask" "F.Paste")
			(net "P1V0")
		)
		(pad "AU25" smd circle
			(at -4.39928 4.8006 180)
			(size 0.381 0.381)
			(layers "F.Cu" "F.Mask" "F.Paste")
			(net "P1V0")
		)
		(pad "AU26" smd circle
			(at -3.60172 4.8006 180)
			(size 0.381 0.381)
			(layers "F.Cu" "F.Mask" "F.Paste")
			(net "P1V0")
		)
		(pad "AU28" smd circle
			(at -2.79908 4.8006 180)
			(size 0.381 0.381)
			(layers "F.Cu" "F.Mask" "F.Paste")
			(net "P1V0")
		)
		(pad "AU29" smd circle
			(at -2.00152 4.8006 180)
			(size 0.381 0.381)
			(layers "F.Cu" "F.Mask" "F.Paste")
			(net "VCCCLKDDR0")
		)
		(pad "AU31" smd circle
			(at -1.19888 4.8006 180)
			(size 0.381 0.381)
			(layers "F.Cu" "F.Mask" "F.Paste")
			(net "VCCA_PLLDDR0_AVN")
		)
		(pad "AU32" smd circle
			(at -0.40132 4.8006 180)
			(size 0.381 0.381)
			(layers "F.Cu" "F.Mask" "F.Paste")
			(net "VCCACKDDR0")
		)
		(pad "AU34" smd circle
			(at 0.40132 4.8006 180)
			(size 0.381 0.381)
			(layers "F.Cu" "F.Mask" "F.Paste")
			(net "TP_CPU_RSVD0")
		)
		(pad "AU36" smd circle
			(at 1.19888 4.8006 180)
			(size 0.381 0.381)
			(layers "F.Cu" "F.Mask" "F.Paste")
			(net "P1V0")
		)
		(pad "AU38" smd circle
			(at 2.00152 4.8006 180)
			(size 0.381 0.381)
			(layers "F.Cu" "F.Mask" "F.Paste")
			(net "P1V0")
		)
		(pad "AU39" smd circle
			(at 2.79908 4.8006 180)
			(size 0.381 0.381)
			(layers "F.Cu" "F.Mask" "F.Paste")
			(net "P1V0")
		)
		(pad "AU41" smd circle
			(at 3.60172 4.8006 180)
			(size 0.381 0.381)
			(layers "F.Cu" "F.Mask" "F.Paste")
			(net "P1V0")
		)
		(pad "AU42" smd circle
			(at 4.39928 4.8006 180)
			(size 0.381 0.381)
			(layers "F.Cu" "F.Mask" "F.Paste")
			(net "P3V3_CPU")
		)
		(pad "AU44" smd circle
			(at 5.20192 4.8006 180)
			(size 0.381 0.381)
			(layers "F.Cu" "F.Mask" "F.Paste")
			(net "GND")
		)
		(pad "AU46" smd circle
			(at 5.99948 4.8006 180)
			(size 0.381 0.381)
			(layers "F.Cu" "F.Mask" "F.Paste")
			(net "P1V8_STBY")
		)
		(pad "AU47" smd circle
			(at 6.72592 4.8006 180)
			(size 0.3048 0.3048)
			(layers "F.Cu" "F.Mask" "F.Paste")
			(net "P1V8_STBY")
		)
		(pad "AU62" smd circle
			(at 14.06398 4.90982 180)
			(size 0.3048 0.3048)
			(layers "F.Cu" "F.Mask" "F.Paste")
			(net "GND")
		)
		(pad "AV2" smd circle
			(at -15.80642 5.36702 180)
			(size 0.3048 0.3048)
			(layers "F.Cu" "F.Mask" "F.Paste")
			(net "GND")
		)
		(pad "AV4" smd circle
			(at -14.75232 5.28574 180)
			(size 0.3048 0.3048)
			(layers "F.Cu" "F.Mask" "F.Paste")
			(net "GND")
		)
		(pad "AV5" smd circle
			(at -14.06398 5.1181 180)
			(size 0.3048 0.3048)
			(layers "F.Cu" "F.Mask" "F.Paste")
			(net "GND")
		)
		(pad "AV63" smd circle
			(at 14.7955 5.0673 180)
			(size 0.3048 0.3048)
			(layers "F.Cu" "F.Mask" "F.Paste")
			(net "XDP_DFX_PORT_CLK0")
		)
		(pad "AV65" smd circle
			(at 15.75308 5.12064 180)
			(size 0.3048 0.3048)
			(layers "F.Cu" "F.Mask" "F.Paste")
			(net "XDP_DFX_PORT_CLK1")
		)
		(pad "AW3" smd circle
			(at -15.24762 5.78866 180)
			(size 0.3048 0.3048)
			(layers "F.Cu" "F.Mask" "F.Paste")
			(net "M_A_ECC4")
		)
		(pad "AW5" smd circle
			(at -14.01318 5.81914 180)
			(size 0.3048 0.3048)
			(layers "F.Cu" "F.Mask" "F.Paste")
			(net "GND")
		)
		(pad "AW8" smd circle
			(at -12.96416 5.7277 180)
			(size 0.3048 0.3048)
			(layers "F.Cu" "F.Mask" "F.Paste")
			(net "M_A_DQ20")
		)
		(pad "AW9" smd circle
			(at -12.20216 5.7277 180)
			(size 0.3048 0.3048)
			(layers "F.Cu" "F.Mask" "F.Paste")
			(net "GND")
		)
		(pad "AW11" smd circle
			(at -11.44016 5.7277 180)
			(size 0.3048 0.3048)
			(layers "F.Cu" "F.Mask" "F.Paste")
			(net "M_A_DQS_DN2")
		)
		(pad "AW12" smd circle
			(at -10.67816 5.7277 180)
			(size 0.3048 0.3048)
			(layers "F.Cu" "F.Mask" "F.Paste")
			(net "M_A_DQS_DP2")
		)
		(pad "AW14" smd circle
			(at -9.91616 5.7277 180)
			(size 0.3048 0.3048)
			(layers "F.Cu" "F.Mask" "F.Paste")
			(net "GND")
		)
		(pad "AW15" smd circle
			(at -9.15416 5.7277 180)
			(size 0.3048 0.3048)
			(layers "F.Cu" "F.Mask" "F.Paste")
			(net "M_A_DQ23")
		)
		(pad "AW17" smd circle
			(at -8.17626 5.77342 180)
			(size 0.3048 0.3048)
			(layers "F.Cu" "F.Mask" "F.Paste")
			(net "M_A_DQ19")
		)
		(pad "AW19" smd circle
			(at -7.47522 5.77342 180)
			(size 0.3048 0.3048)
			(layers "F.Cu" "F.Mask" "F.Paste")
			(net "GND")
		)
		(pad "AW20" smd circle
			(at -6.80212 5.50164 180)
			(size 0.3048 0.3048)
			(layers "F.Cu" "F.Mask" "F.Paste")
			(net "M_A_ODTPU")
		)
		(pad "AW21" smd circle
			(at -5.90042 5.50164 180)
			(size 0.3048 0.3048)
			(layers "F.Cu" "F.Mask" "F.Paste")
			(net "M_A_DQPU")
		)
		(pad "AW23" smd circle
			(at -5.20192 5.50164 180)
			(size 0.381 0.381)
			(layers "F.Cu" "F.Mask" "F.Paste")
			(net "GND")
		)
		(pad "AW25" smd circle
			(at -4.2037 5.77342 180)
			(size 0.3048 0.3048)
			(layers "F.Cu" "F.Mask" "F.Paste")
			(net "GND")
		)
		(pad "AW26" smd circle
			(at -3.50266 5.77342 180)
			(size 0.3048 0.3048)
			(layers "F.Cu" "F.Mask" "F.Paste")
			(net "GND")
		)
		(pad "AW28" smd circle
			(at -2.79908 5.50164 180)
			(size 0.381 0.381)
			(layers "F.Cu" "F.Mask" "F.Paste")
			(net "GND")
		)
		(pad "AW30" smd circle
			(at -1.89992 5.50164 180)
			(size 0.381 0.381)
			(layers "F.Cu" "F.Mask" "F.Paste")
			(net "GND")
		)
		(pad "AW31" smd circle
			(at -1.19888 5.50164 180)
			(size 0.381 0.381)
			(layers "F.Cu" "F.Mask" "F.Paste")
			(net "GND")
		)
		(pad "AW32" smd circle
			(at -0.23114 5.77342 180)
			(size 0.3048 0.3048)
			(layers "F.Cu" "F.Mask" "F.Paste")
			(net "GND")
		)
		(pad "AW34" smd circle
			(at 0.4699 5.77342 180)
			(size 0.3048 0.3048)
			(layers "F.Cu" "F.Mask" "F.Paste")
			(net "GND")
		)
		(pad "AW36" smd circle
			(at 1.19888 5.50164 180)
			(size 0.381 0.381)
			(layers "F.Cu" "F.Mask" "F.Paste")
			(net "P1V0")
		)
		(pad "AW38" smd circle
			(at 2.10058 5.50164 180)
			(size 0.381 0.381)
			(layers "F.Cu" "F.Mask" "F.Paste")
			(net "P1V0")
		)
		(pad "AW39" smd circle
			(at 2.79908 5.50164 180)
			(size 0.381 0.381)
			(layers "F.Cu" "F.Mask" "F.Paste")
			(net "P1V0")
		)
		(pad "AW41" smd circle
			(at 3.74142 5.77342 180)
			(size 0.3048 0.3048)
			(layers "F.Cu" "F.Mask" "F.Paste")
			(net "P1V0")
		)
		(pad "AW42" smd circle
			(at 4.44246 5.77342 180)
			(size 0.3048 0.3048)
			(layers "F.Cu" "F.Mask" "F.Paste")
			(net "P3V3_CPU")
		)
		(pad "AW44" smd circle
			(at 5.20192 5.50164 180)
			(size 0.381 0.381)
			(layers "F.Cu" "F.Mask" "F.Paste")
			(net "GND")
		)
		(pad "AW46" smd circle
			(at 5.99948 5.50164 180)
			(size 0.3048 0.3048)
			(layers "F.Cu" "F.Mask" "F.Paste")
			(net "GND")
		)
		(pad "AW47" smd circle
			(at 6.70052 5.50164 180)
			(size 0.3048 0.3048)
			(layers "F.Cu" "F.Mask" "F.Paste")
			(net "GND")
		)
		(pad "AW49" smd circle
			(at 7.71398 5.77342 180)
			(size 0.3048 0.3048)
			(layers "F.Cu" "F.Mask" "F.Paste")
			(net "GND")
		)
		(pad "AW50" smd circle
			(at 8.41502 5.77342 180)
			(size 0.3048 0.3048)
			(layers "F.Cu" "F.Mask" "F.Paste")
			(net "GND")
		)
		(pad "AW52" smd circle
			(at 9.15416 5.48894 180)
			(size 0.3048 0.3048)
			(layers "F.Cu" "F.Mask" "F.Paste")
			(net "GND")
		)
		(pad "AW53" smd circle
			(at 9.91616 5.48894 180)
			(size 0.3048 0.3048)
			(layers "F.Cu" "F.Mask" "F.Paste")
			(net "SVID_DATA_R")
		)
		(pad "AW55" smd circle
			(at 10.67816 5.48894 180)
			(size 0.3048 0.3048)
			(layers "F.Cu" "F.Mask" "F.Paste")
			(net "GND")
		)
		(pad "AW56" smd circle
			(at 11.44016 5.48894 180)
			(size 0.3048 0.3048)
			(layers "F.Cu" "F.Mask" "F.Paste")
			(net "XDP_CPU_PRDY#")
		)
		(pad "AW58" smd circle
			(at 12.20216 5.48894 180)
			(size 0.3048 0.3048)
			(layers "F.Cu" "F.Mask" "F.Paste")
			(net "XDP_DFX_PORT2")
		)
		(pad "AW59" smd circle
			(at 12.96416 5.48894 180)
			(size 0.3048 0.3048)
			(layers "F.Cu" "F.Mask" "F.Paste")
			(net "GND")
		)
		(pad "AW62" smd circle
			(at 14.08176 5.61848 180)
			(size 0.3048 0.3048)
			(layers "F.Cu" "F.Mask" "F.Paste")
			(net "XDP_DFX_PORT7")
		)
	)
)
